(kicad_pcb
	(version 20260206)
	(generator "pcbnew")
	(generator_version "10.0")
	(general
		(thickness 1.6)
		(legacy_teardrops no)
	)
	(paper "A4")
	(title_block
		(title "baseboard — 13948-1b.1110WZS1818.brd")
		(comment 1 "Honey Badger (Wiwynn) / footprints 2165-2172 of 2523")
	)
	(layers
		(0 "F.Cu" signal "TOP")
		(4 "In1.Cu" signal "L2GND")
		(6 "In2.Cu" signal "L3")
		(8 "In3.Cu" signal "L4VCC")
		(10 "In4.Cu" signal "L5VCC")
		(12 "In5.Cu" signal "L6")
		(14 "In6.Cu" signal "L7GND")
		(2 "B.Cu" signal "BOTTOM")
		(9 "F.Adhes" user "F.Adhesive")
		(11 "B.Adhes" user "B.Adhesive")
		(13 "F.Paste" user "Package Geometry/Pastemask Top")
		(15 "B.Paste" user "Package Geometry/Pastemask Bottom")
		(5 "F.SilkS" user "Ref Des/Silkscreen Top")
		(7 "B.SilkS" user "Ref Des/Silkscreen Bottom")
		(1 "F.Mask" user "Board Geometry/Soldermask Top")
		(3 "B.Mask" user "Board Geometry/Soldermask Bottom")
		(17 "Dwgs.User" user "User.Drawings")
		(19 "Cmts.User" user "User.Comments")
		(21 "Eco1.User" user "User.Eco1")
		(23 "Eco2.User" user "User.Eco2")
		(25 "Edge.Cuts" user "Board Geometry/Outline")
		(27 "Margin" user)
		(31 "F.CrtYd" user "Package Geometry/Place Bound Top")
		(29 "B.CrtYd" user "Package Geometry/Place Bound Bottom")
		(35 "F.Fab" user "Ref Des/Assembly Top")
		(33 "B.Fab" user "Ref Des/Assembly Bottom")
	)
	(footprint ""
		(layer "B.Cu")
		(at 161.417 -89.154)
		(property "Reference" "PC177"
			(at 0 0 0)
			(layer "B.SilkS")
			(hide yes)
			(effects
				(font
					(size 1.27 1.27)
				)
				(justify mirror)
			)
		)
		(property "Value" "SC22U6D3V3MX-1-GP"
			(at 0 -2.8194 0)
			(unlocked yes)
			(layer "B.Fab")
			(hide yes)
			(effects
				(font
					(size 1.016 1.016)
					(thickness 0.1524)
				)
				(justify mirror)
			)
		)
		(property "Device Type" "C603H40"
			(at 0 -4.3434 0)
			(unlocked yes)
			(layer "B.Fab")
			(hide yes)
			(effects
				(font
					(size 1.016 1.016)
					(thickness 0.1524)
				)
				(justify mirror)
			)
		)
		(duplicate_pad_numbers_are_jumpers no)
		(fp_line
			(start -0.508 0)
			(end 0.508 0)
			(stroke
				(width 0.2032)
				(type default)
			)
			(layer "B.SilkS")
		)
		(fp_rect
			(start 0.5842 1.3335)
			(end -0.5842 -1.3335)
			(stroke
				(width 0)
				(type default)
			)
			(fill no)
			(layer "B.CrtYd")
		)
		(fp_rect
			(start 0.5842 1.3335)
			(end -0.5842 -1.3335)
			(stroke
				(width 0)
				(type default)
			)
			(fill no)
			(layer "B.Fab")
		)
		(pad "1" smd custom
			(at 0 -0.762 180)
			(size 0.2159 0.2159)
			(layers "B.Cu" "B.Mask" "B.Paste")
			(net "P0V9_E")
			(options
				(clearance outline)
				(anchor circle)
			)
			(primitives
				(gr_poly
					(pts
						(arc
							(start -0.3302 0.4318)
							(mid -0.402042 0.402042)
							(end -0.4318 0.3302)
						)
						(arc
							(start -0.4318 -0.3302)
							(mid -0.402042 -0.402042)
							(end -0.3302 -0.4318)
						)
						(arc
							(start 0.3302 -0.4318)
							(mid 0.402042 -0.402042)
							(end 0.4318 -0.3302)
						)
						(arc
							(start 0.4318 0.3302)
							(mid 0.402042 0.402042)
							(end 0.3302 0.4318)
						)
					)
					(width 0)
					(fill yes)
				)
			)
		)
		(pad "2" smd custom
			(at 0 0.762 180)
			(size 0.2159 0.2159)
			(layers "B.Cu" "B.Mask" "B.Paste")
			(net "GND")
			(options
				(clearance outline)
				(anchor circle)
			)
			(primitives
				(gr_poly
					(pts
						(arc
							(start -0.3302 0.4318)
							(mid -0.402042 0.402042)
							(end -0.4318 0.3302)
						)
						(arc
							(start -0.4318 -0.3302)
							(mid -0.402042 -0.402042)
							(end -0.3302 -0.4318)
						)
						(arc
							(start 0.3302 -0.4318)
							(mid 0.402042 -0.402042)
							(end 0.4318 -0.3302)
						)
						(arc
							(start 0.4318 0.3302)
							(mid 0.402042 0.402042)
							(end 0.3302 0.4318)
						)
					)
					(width 0)
					(fill yes)
				)
			)
		)
	)
	(footprint ""
		(layer "B.Cu")
		(at 108.020612 -212.725 -90)
		(property "Reference" "SR902"
			(at 0 0 90)
			(layer "B.SilkS")
			(hide yes)
			(effects
				(font
					(size 1.27 1.27)
				)
				(justify mirror)
			)
		)
		(property "Value" "4K7R2F-GP"
			(at -0.064008 -3.993896 270)
			(unlocked yes)
			(layer "B.Fab")
			(hide yes)
			(effects
				(font
					(size 1.016 1.016)
					(thickness 0.1524)
				)
				(justify mirror)
			)
		)
		(property "Device Type" "R402H16"
			(at -0.064008 -5.517896 270)
			(unlocked yes)
			(layer "B.Fab")
			(hide yes)
			(effects
				(font
					(size 1.016 1.016)
					(thickness 0.1524)
				)
				(justify mirror)
			)
		)
		(duplicate_pad_numbers_are_jumpers no)
		(fp_line
			(start -0.508 -0.9398)
			(end 0.508 -0.9398)
			(stroke
				(width 0.1524)
				(type default)
			)
			(layer "B.SilkS")
		)
		(fp_line
			(start 0.508 -0.9398)
			(end 0.508 0.9398)
			(stroke
				(width 0.1524)
				(type default)
			)
			(layer "B.SilkS")
		)
		(fp_rect
			(start 0.508 0.9398)
			(end -0.508 -0.9398)
			(stroke
				(width 0)
				(type default)
			)
			(fill no)
			(layer "B.CrtYd")
		)
		(fp_rect
			(start 0.508 0.9398)
			(end -0.508 -0.9398)
			(stroke
				(width 0)
				(type default)
			)
			(fill no)
			(layer "B.Fab")
		)
		(pad "1" smd custom
			(at 0 -0.4445 90)
			(size 0.1397 0.1397)
			(layers "B.Cu" "B.Mask" "B.Paste")
			(net "REDV_I2C_A4")
			(options
				(clearance outline)
				(anchor circle)
			)
			(primitives
				(gr_poly
					(pts
						(arc
							(start -0.1778 0.2794)
							(mid -0.249642 0.249642)
							(end -0.2794 0.1778)
						)
						(arc
							(start -0.2794 -0.1778)
							(mid -0.249642 -0.249642)
							(end -0.1778 -0.2794)
						)
						(arc
							(start 0.1778 -0.2794)
							(mid 0.249642 -0.249642)
							(end 0.2794 -0.1778)
						)
						(arc
							(start 0.2794 0.1778)
							(mid 0.249642 0.249642)
							(end 0.1778 0.2794)
						)
					)
					(width 0)
					(fill yes)
				)
			)
		)
		(pad "2" smd custom
			(at 0 0.4445 90)
			(size 0.1397 0.1397)
			(layers "B.Cu" "B.Mask" "B.Paste")
			(net "GND")
			(options
				(clearance outline)
				(anchor circle)
			)
			(primitives
				(gr_poly
					(pts
						(arc
							(start -0.1778 0.2794)
							(mid -0.249642 0.249642)
							(end -0.2794 0.1778)
						)
						(arc
							(start -0.2794 -0.1778)
							(mid -0.249642 -0.249642)
							(end -0.1778 -0.2794)
						)
						(arc
							(start 0.1778 -0.2794)
							(mid 0.249642 -0.249642)
							(end 0.2794 -0.1778)
						)
						(arc
							(start 0.2794 0.1778)
							(mid 0.249642 0.249642)
							(end 0.1778 0.2794)
						)
					)
					(width 0)
					(fill yes)
				)
			)
		)
	)
	(footprint ""
		(layer "B.Cu")
		(at 102.75697 -104.648)
		(property "Reference" "STP90"
			(at 0 0 0)
			(layer "B.SilkS")
			(hide yes)
			(effects
				(font
					(size 1.27 1.27)
				)
				(justify mirror)
			)
		)
		(property "Value" "TPAD28"
			(at -0.0127 -1.8034 0)
			(unlocked yes)
			(layer "B.Fab")
			(hide yes)
			(effects
				(font
					(size 1.016 1.016)
					(thickness 0.1524)
				)
				(justify mirror)
			)
		)
		(property "Device Type" "TPAD28"
			(at -0.0127 -3.3274 0)
			(unlocked yes)
			(layer "B.Fab")
			(hide yes)
			(effects
				(font
					(size 1.016 1.016)
					(thickness 0.1524)
				)
				(justify mirror)
			)
		)
		(duplicate_pad_numbers_are_jumpers no)
		(fp_poly
			(pts
				(arc
					(start 0.3556 0)
					(mid -0.3556 0)
					(end 0.3556 0)
				)
			)
			(stroke
				(width 0)
				(type default)
			)
			(fill no)
			(layer "B.CrtYd")
		)
		(fp_poly
			(pts
				(arc
					(start 0.6096 0)
					(mid -0.6096 0)
					(end 0.6096 0)
				)
			)
			(stroke
				(width 0)
				(type default)
			)
			(fill no)
			(layer "B.Fab")
		)
		(pad "1" smd circle
			(at 0 0 180)
			(size 0.7112 0.7112)
			(layers "B.Cu" "B.Mask" "B.Paste")
			(net "PHY_CLK")
		)
	)
	(footprint ""
		(layer "B.Cu")
		(at 97.03816 -31.623)
		(property "Reference" "SC866"
			(at 0 0 0)
			(layer "B.SilkS")
			(hide yes)
			(effects
				(font
					(size 1.27 1.27)
				)
				(justify mirror)
			)
		)
		(property "Value" "SCD22U6D3V1MX-1-GP"
			(at 2.8321 -1.7399 0)
			(unlocked yes)
			(layer "B.Fab")
			(hide yes)
			(effects
				(font
					(size 1.016 1.016)
					(thickness 0.1524)
				)
				(justify mirror)
			)
		)
		(property "Device Type" "C0201H13"
			(at 2.8321 -3.2639 0)
			(unlocked yes)
			(layer "B.Fab")
			(hide yes)
			(effects
				(font
					(size 1.016 1.016)
					(thickness 0.1524)
				)
				(justify mirror)
			)
		)
		(duplicate_pad_numbers_are_jumpers no)
		(fp_rect
			(start 0.2794 0.6477)
			(end -0.2794 -0.6477)
			(stroke
				(width 0)
				(type default)
			)
			(fill no)
			(layer "B.CrtYd")
		)
		(fp_rect
			(start 0.2794 0.6477)
			(end -0.2794 -0.6477)
			(stroke
				(width 0)
				(type default)
			)
			(fill no)
			(layer "B.Fab")
		)
		(pad "1" smd custom
			(at 0 -0.2794 180)
			(size 0.0762 0.0762)
			(layers "B.Cu" "B.Mask" "B.Paste")
			(net "PCIE_SAS_C_CPU_RX_N2")
			(options
				(clearance outline)
				(anchor circle)
			)
			(primitives
				(gr_poly
					(pts
						(arc
							(start 0.1524 0.127)
							(mid 0.137521 0.162921)
							(end 0.1016 0.1778)
						)
						(arc
							(start -0.1016 0.1778)
							(mid -0.137521 0.162921)
							(end -0.1524 0.127)
						)
						(arc
							(start -0.1524 -0.127)
							(mid -0.137521 -0.162921)
							(end -0.1016 -0.1778)
						)
						(arc
							(start 0.1016 -0.1778)
							(mid 0.137521 -0.162921)
							(end 0.1524 -0.127)
						)
					)
					(width 0)
					(fill yes)
				)
			)
		)
		(pad "2" smd custom
			(at 0 0.2794 180)
			(size 0.0762 0.0762)
			(layers "B.Cu" "B.Mask" "B.Paste")
			(net "PCIE_SAS_CPU_RX_N2")
			(options
				(clearance outline)
				(anchor circle)
			)
			(primitives
				(gr_poly
					(pts
						(arc
							(start 0.1524 0.127)
							(mid 0.137521 0.162921)
							(end 0.1016 0.1778)
						)
						(arc
							(start -0.1016 0.1778)
							(mid -0.137521 0.162921)
							(end -0.1524 0.127)
						)
						(arc
							(start -0.1524 -0.127)
							(mid -0.137521 -0.162921)
							(end -0.1016 -0.1778)
						)
						(arc
							(start 0.1016 -0.1778)
							(mid 0.137521 -0.162921)
							(end 0.1524 -0.127)
						)
					)
					(width 0)
					(fill yes)
				)
			)
		)
	)
	(footprint ""
		(layer "B.Cu")
		(at 295.021 -178.943 -90)
		(property "Reference" "C211"
			(at 0 0 90)
			(layer "B.SilkS")
			(hide yes)
			(effects
				(font
					(size 1.27 1.27)
				)
				(justify mirror)
			)
		)
		(property "Value" "SC220P50V2KX-3GP"
			(at -1.1811 -2.7051 270)
			(unlocked yes)
			(layer "B.Fab")
			(hide yes)
			(effects
				(font
					(size 1.016 1.016)
					(thickness 0.1524)
				)
				(justify mirror)
			)
		)
		(property "Device Type" "C402H22"
			(at -1.1811 -4.2291 270)
			(unlocked yes)
			(layer "B.Fab")
			(hide yes)
			(effects
				(font
					(size 1.016 1.016)
					(thickness 0.1524)
				)
				(justify mirror)
			)
		)
		(duplicate_pad_numbers_are_jumpers no)
		(fp_rect
			(start 0.4318 0.9525)
			(end -0.4318 -0.9525)
			(stroke
				(width 0)
				(type default)
			)
			(fill no)
			(layer "B.CrtYd")
		)
		(fp_rect
			(start 0.4318 0.9525)
			(end -0.4318 -0.9525)
			(stroke
				(width 0)
				(type default)
			)
			(fill no)
			(layer "B.Fab")
		)
		(pad "1" smd custom
			(at 0 -0.4445 90)
			(size 0.1524 0.1524)
			(layers "B.Cu" "B.Mask" "B.Paste")
			(net "P3V3_STBY")
			(options
				(clearance outline)
				(anchor circle)
			)
			(primitives
				(gr_poly
					(pts
						(arc
							(start 0.3048 0.2032)
							(mid 0.275042 0.275042)
							(end 0.2032 0.3048)
						)
						(arc
							(start -0.2032 0.3048)
							(mid -0.275042 0.275042)
							(end -0.3048 0.2032)
						)
						(arc
							(start -0.3048 -0.2032)
							(mid -0.275042 -0.275042)
							(end -0.2032 -0.3048)
						)
						(arc
							(start 0.2032 -0.3048)
							(mid 0.275042 -0.275042)
							(end 0.3048 -0.2032)
						)
					)
					(width 0)
					(fill yes)
				)
			)
		)
		(pad "2" smd custom
			(at 0 0.4445 90)
			(size 0.1524 0.1524)
			(layers "B.Cu" "B.Mask" "B.Paste")
			(net "GND")
			(options
				(clearance outline)
				(anchor circle)
			)
			(primitives
				(gr_poly
					(pts
						(arc
							(start 0.3048 0.2032)
							(mid 0.275042 0.275042)
							(end 0.2032 0.3048)
						)
						(arc
							(start -0.2032 0.3048)
							(mid -0.275042 0.275042)
							(end -0.3048 0.2032)
						)
						(arc
							(start -0.3048 -0.2032)
							(mid -0.275042 -0.275042)
							(end -0.2032 -0.3048)
						)
						(arc
							(start 0.2032 -0.3048)
							(mid 0.275042 -0.275042)
							(end 0.3048 -0.2032)
						)
					)
					(width 0)
					(fill yes)
				)
			)
		)
	)
	(footprint ""
		(layer "B.Cu")
		(at 318.008 -167.894 -90)
		(property "Reference" "R246"
			(at 0 0 90)
			(layer "B.SilkS")
			(hide yes)
			(effects
				(font
					(size 1.27 1.27)
				)
				(justify mirror)
			)
		)
		(property "Value" "0R2J-2-GP"
			(at -0.064008 -3.993896 270)
			(unlocked yes)
			(layer "B.Fab")
			(hide yes)
			(effects
				(font
					(size 1.016 1.016)
					(thickness 0.1524)
				)
				(justify mirror)
			)
		)
		(property "Device Type" "R402H16"
			(at -0.064008 -5.517896 270)
			(unlocked yes)
			(layer "B.Fab")
			(hide yes)
			(effects
				(font
					(size 1.016 1.016)
					(thickness 0.1524)
				)
				(justify mirror)
			)
		)
		(duplicate_pad_numbers_are_jumpers no)
		(fp_line
			(start -0.508 -0.9398)
			(end 0.508 -0.9398)
			(stroke
				(width 0.1524)
				(type default)
			)
			(layer "B.SilkS")
		)
		(fp_line
			(start 0.508 -0.9398)
			(end 0.508 0.9398)
			(stroke
				(width 0.1524)
				(type default)
			)
			(layer "B.SilkS")
		)
		(fp_rect
			(start 0.508 0.9398)
			(end -0.508 -0.9398)
			(stroke
				(width 0)
				(type default)
			)
			(fill no)
			(layer "B.CrtYd")
		)
		(fp_rect
			(start 0.508 0.9398)
			(end -0.508 -0.9398)
			(stroke
				(width 0)
				(type default)
			)
			(fill no)
			(layer "B.Fab")
		)
		(pad "1" smd custom
			(at 0 -0.4445 90)
			(size 0.1397 0.1397)
			(layers "B.Cu" "B.Mask" "B.Paste")
			(net "BMC_I2C_A_SCL")
			(options
				(clearance outline)
				(anchor circle)
			)
			(primitives
				(gr_poly
					(pts
						(arc
							(start -0.1778 0.2794)
							(mid -0.249642 0.249642)
							(end -0.2794 0.1778)
						)
						(arc
							(start -0.2794 -0.1778)
							(mid -0.249642 -0.249642)
							(end -0.1778 -0.2794)
						)
						(arc
							(start 0.1778 -0.2794)
							(mid 0.249642 -0.249642)
							(end 0.2794 -0.1778)
						)
						(arc
							(start 0.2794 0.1778)
							(mid 0.249642 0.249642)
							(end 0.1778 0.2794)
						)
					)
					(width 0)
					(fill yes)
				)
			)
		)
		(pad "2" smd custom
			(at 0 0.4445 90)
			(size 0.1397 0.1397)
			(layers "B.Cu" "B.Mask" "B.Paste")
			(net "BMC0_SMB5_CLK")
			(options
				(clearance outline)
				(anchor circle)
			)
			(primitives
				(gr_poly
					(pts
						(arc
							(start -0.1778 0.2794)
							(mid -0.249642 0.249642)
							(end -0.2794 0.1778)
						)
						(arc
							(start -0.2794 -0.1778)
							(mid -0.249642 -0.249642)
							(end -0.1778 -0.2794)
						)
						(arc
							(start 0.1778 -0.2794)
							(mid 0.249642 -0.249642)
							(end 0.2794 -0.1778)
						)
						(arc
							(start 0.2794 0.1778)
							(mid 0.249642 0.249642)
							(end 0.1778 0.2794)
						)
					)
					(width 0)
					(fill yes)
				)
			)
		)
	)
	(footprint ""
		(layer "B.Cu")
		(at 324.358 -175.006 180)
		(property "Reference" "R5766"
			(at 0 0 0)
			(layer "B.SilkS")
			(hide yes)
			(effects
				(font
					(size 1.27 1.27)
				)
				(justify mirror)
			)
		)
		(property "Value" "1KR2F-3-GP"
			(at -0.064008 -3.993896 180)
			(unlocked yes)
			(layer "B.Fab")
			(hide yes)
			(effects
				(font
					(size 1.016 1.016)
					(thickness 0.1524)
				)
				(justify mirror)
			)
		)
		(property "Device Type" "R402H16"
			(at -0.064008 -5.517896 180)
			(unlocked yes)
			(layer "B.Fab")
			(hide yes)
			(effects
				(font
					(size 1.016 1.016)
					(thickness 0.1524)
				)
				(justify mirror)
			)
		)
		(duplicate_pad_numbers_are_jumpers no)
		(fp_line
			(start 0.508 -0.9398)
			(end 0.508 0.9398)
			(stroke
				(width 0.1524)
				(type default)
			)
			(layer "B.SilkS")
		)
		(fp_line
			(start -0.508 -0.9398)
			(end 0.508 -0.9398)
			(stroke
				(width 0.1524)
				(type default)
			)
			(layer "B.SilkS")
		)
		(fp_rect
			(start 0.508 0.9398)
			(end -0.508 -0.9398)
			(stroke
				(width 0)
				(type default)
			)
			(fill no)
			(layer "B.CrtYd")
		)
		(fp_rect
			(start 0.508 0.9398)
			(end -0.508 -0.9398)
			(stroke
				(width 0)
				(type default)
			)
			(fill no)
			(layer "B.Fab")
		)
		(pad "1" smd custom
			(at 0 -0.4445)
			(size 0.1397 0.1397)
			(layers "B.Cu" "B.Mask" "B.Paste")
			(net "ADC_12V")
			(options
				(clearance outline)
				(anchor circle)
			)
			(primitives
				(gr_poly
					(pts
						(arc
							(start -0.1778 0.2794)
							(mid -0.249642 0.249642)
							(end -0.2794 0.1778)
						)
						(arc
							(start -0.2794 -0.1778)
							(mid -0.249642 -0.249642)
							(end -0.1778 -0.2794)
						)
						(arc
							(start 0.1778 -0.2794)
							(mid 0.249642 -0.249642)
							(end 0.2794 -0.1778)
						)
						(arc
							(start 0.2794 0.1778)
							(mid 0.249642 0.249642)
							(end 0.1778 0.2794)
						)
					)
					(width 0)
					(fill yes)
				)
			)
		)
		(pad "2" smd custom
			(at 0 0.4445)
			(size 0.1397 0.1397)
			(layers "B.Cu" "B.Mask" "B.Paste")
			(net "GND")
			(options
				(clearance outline)
				(anchor circle)
			)
			(primitives
				(gr_poly
					(pts
						(arc
							(start -0.1778 0.2794)
							(mid -0.249642 0.249642)
							(end -0.2794 0.1778)
						)
						(arc
							(start -0.2794 -0.1778)
							(mid -0.249642 -0.249642)
							(end -0.1778 -0.2794)
						)
						(arc
							(start 0.1778 -0.2794)
							(mid 0.249642 -0.249642)
							(end 0.2794 -0.1778)
						)
						(arc
							(start 0.2794 0.1778)
							(mid 0.249642 0.249642)
							(end 0.1778 0.2794)
						)
					)
					(width 0)
					(fill yes)
				)
			)
		)
	)
	(footprint ""
		(layer "B.Cu")
		(at 289.24504 -170.57624)
		(property "Reference" "TP137"
			(at 0 0 0)
			(layer "B.SilkS")
			(hide yes)
			(effects
				(font
					(size 1.27 1.27)
				)
				(justify mirror)
			)
		)
		(property "Value" "TPAD28"
			(at -0.0127 -1.8034 0)
			(unlocked yes)
			(layer "B.Fab")
			(hide yes)
			(effects
				(font
					(size 1.016 1.016)
					(thickness 0.1524)
				)
				(justify mirror)
			)
		)
		(property "Device Type" "TPAD28"
			(at -0.0127 -3.3274 0)
			(unlocked yes)
			(layer "B.Fab")
			(hide yes)
			(effects
				(font
					(size 1.016 1.016)
					(thickness 0.1524)
				)
				(justify mirror)
			)
		)
		(duplicate_pad_numbers_are_jumpers no)
		(fp_poly
			(pts
				(arc
					(start 0.3556 0)
					(mid -0.3556 0)
					(end 0.3556 0)
				)
			)
			(stroke
				(width 0)
				(type default)
			)
			(fill no)
			(layer "B.CrtYd")
		)
		(fp_poly
			(pts
				(arc
					(start 0.6096 0)
					(mid -0.6096 0)
					(end 0.6096 0)
				)
			)
			(stroke
				(width 0)
				(type default)
			)
			(fill no)
			(layer "B.Fab")
		)
		(pad "1" smd circle
			(at 0 0 180)
			(size 0.7112 0.7112)
			(layers "B.Cu" "B.Mask" "B.Paste")
			(net "TP_BMC_GPIOE0")
		)
	)
)
